(kicad_pcb
	(version 20260206)
	(generator "pcbnew")
	(generator_version "10.0")
	(general
		(thickness 1.6)
		(legacy_teardrops no)
	)
	(paper "A4")
	(title_block
		(title "v1-chassis-manager — T6M_CM_d_v01_1031_1645.brd")
		(comment 1 "Open CloudServer (Microsoft) / footprints 589-595 of 2512")
	)
	(layers
		(0 "F.Cu" signal "TOP")
		(4 "In1.Cu" signal "GND1")
		(6 "In2.Cu" signal "IN1")
		(8 "In3.Cu" signal "VCC1")
		(10 "In4.Cu" signal "VCC2")
		(12 "In5.Cu" signal "GND2")
		(14 "In6.Cu" signal "IN2")
		(16 "In7.Cu" signal "IN3")
		(18 "In8.Cu" signal "GND3")
		(2 "B.Cu" signal "BOTTOM")
		(9 "F.Adhes" user "F.Adhesive")
		(11 "B.Adhes" user "B.Adhesive")
		(13 "F.Paste" user "Package Geometry/Pastemask Top")
		(15 "B.Paste" user "Package Geometry/Pastemask Bottom")
		(5 "F.SilkS" user "Ref Des/Silkscreen Top")
		(7 "B.SilkS" user "Ref Des/Silkscreen Bottom")
		(1 "F.Mask" user "Board Geometry/Soldermask Top")
		(3 "B.Mask" user "Board Geometry/Soldermask Bottom")
		(17 "Dwgs.User" user "User.Drawings")
		(19 "Cmts.User" user "User.Comments")
		(21 "Eco1.User" user "User.Eco1")
		(23 "Eco2.User" user "User.Eco2")
		(25 "Edge.Cuts" user "Board Geometry/Outline")
		(27 "Margin" user)
		(31 "F.CrtYd" user "Package Geometry/Place Bound Top")
		(29 "B.CrtYd" user "Package Geometry/Place Bound Bottom")
		(35 "F.Fab" user "Ref Des/Assembly Top")
		(33 "B.Fab" user "Ref Des/Assembly Bottom")
	)
	(footprint ""
		(layer "F.Cu")
		(at 36.478718 -113.177828 180)
		(property "Reference" "Q39"
			(at 3.812032 0.982472 90)
			(unlocked yes)
			(layer "F.SilkS")
			(effects
				(font
					(size 0.7874 0.5842)
					(thickness 0.1524)
				)
			)
		)
		(property "Value" ""
			(at 0 0 180)
			(layer "F.Fab")
			(effects
				(font
					(size 1.27 1.27)
				)
			)
		)
		(duplicate_pad_numbers_are_jumpers no)
		(fp_line
			(start 2.899918 2.474976)
			(end 1.755648 2.474976)
			(stroke
				(width 0.1524)
				(type default)
			)
			(layer "F.SilkS")
		)
		(fp_line
			(start 2.899918 2.295906)
			(end 2.899918 2.474976)
			(stroke
				(width 0.1524)
				(type default)
			)
			(layer "F.SilkS")
		)
		(fp_line
			(start 2.899918 -0.525018)
			(end 2.899918 -0.345694)
			(stroke
				(width 0.1524)
				(type default)
			)
			(layer "F.SilkS")
		)
		(fp_line
			(start 1.755648 -0.525018)
			(end 2.899918 -0.525018)
			(stroke
				(width 0.1524)
				(type default)
			)
			(layer "F.SilkS")
		)
		(fp_line
			(start 1.044448 2.474976)
			(end -0.100076 2.474976)
			(stroke
				(width 0.1524)
				(type default)
			)
			(layer "F.SilkS")
		)
		(fp_line
			(start -0.100076 2.474976)
			(end -0.100076 2.295906)
			(stroke
				(width 0.1524)
				(type default)
			)
			(layer "F.SilkS")
		)
		(fp_line
			(start -0.100076 -0.320294)
			(end -0.100076 -0.525018)
			(stroke
				(width 0.1524)
				(type default)
			)
			(layer "F.SilkS")
		)
		(fp_line
			(start -0.100076 -0.525018)
			(end 1.044448 -0.525018)
			(stroke
				(width 0.1524)
				(type default)
			)
			(layer "F.SilkS")
		)
		(fp_poly
			(pts
				(xy -0.350012 -1.286256) (xy 0.16891 -1.286256) (xy -0.094742 -0.708914)
			)
			(stroke
				(width 0)
				(type default)
			)
			(fill yes)
			(layer "F.SilkS")
		)
		(fp_poly
			(pts
				(xy -0.100076 -0.525018) (xy -0.100076 -0.244094) (xy -0.301752 -0.244094) (xy -0.301752 2.194306)
				(xy -0.100076 2.194306) (xy -0.100076 2.474976) (xy 1.120648 2.474976) (xy 1.120648 2.651506) (xy 1.679448 2.651506)
				(xy 1.679448 2.474976) (xy 2.899918 2.474976) (xy 2.899918 2.219706) (xy 3.101848 2.219706) (xy 3.101848 -0.269494)
				(xy 2.899918 -0.269494) (xy 2.899918 -0.525018) (xy 1.679448 -0.525018) (xy 1.679448 -0.701294)
				(xy 1.120648 -0.701294) (xy 1.120648 -0.525018)
			)
			(stroke
				(width 0)
				(type default)
			)
			(fill no)
			(layer "F.CrtYd")
		)
		(fp_line
			(start 2.899918 2.474976)
			(end -0.100076 2.474976)
			(stroke
				(width 0.1)
				(type default)
			)
			(layer "F.Fab")
		)
		(fp_line
			(start 2.899918 -0.525018)
			(end 2.899918 2.474976)
			(stroke
				(width 0.1)
				(type default)
			)
			(layer "F.Fab")
		)
		(fp_line
			(start -0.100076 2.474976)
			(end -0.100076 -0.525018)
			(stroke
				(width 0.1)
				(type default)
			)
			(layer "F.Fab")
		)
		(fp_line
			(start -0.100076 -0.525018)
			(end 2.899918 -0.525018)
			(stroke
				(width 0.1)
				(type default)
			)
			(layer "F.Fab")
		)
		(pad "1" smd rect
			(at 0 0 90)
			(size 0.3556 0.508)
			(layers "F.Cu" "F.Mask" "F.Paste")
			(net "P1V5_NODE1")
		)
		(pad "2" smd rect
			(at 0 0.649986 90)
			(size 0.3556 0.508)
			(layers "F.Cu" "F.Mask" "F.Paste")
			(net "P1V5_NODE1")
		)
		(pad "3" smd rect
			(at 0 1.299972 90)
			(size 0.3556 0.508)
			(layers "F.Cu" "F.Mask" "F.Paste")
			(net "P1V5_NODE1")
		)
		(pad "4" smd rect
			(at 0 1.949958 90)
			(size 0.3556 0.508)
			(layers "F.Cu" "F.Mask" "F.Paste")
			(net "FM_CPLD_NODE1_P1V5_EN_LV")
		)
		(pad "5" smd custom
			(at 1.400048 0.975106 90)
			(size 0.569976 0.569976)
			(layers "F.Cu" "F.Mask" "F.Paste")
			(net "P1V5_SUS_NODE1")
			(options
				(clearance outline)
				(anchor circle)
			)
			(primitives
				(gr_poly
					(pts
						(xy -1.225042 1.139952) (xy -1.225042 0.724916) (xy -1.605026 0.724916) (xy -1.605026 0.295148)
						(xy -1.225042 0.295148) (xy -1.225042 -0.839978) (xy -1.175004 -0.839978) (xy -1.175004 -1.139952)
						(xy -0.774954 -1.139952) (xy -0.774954 -0.839978) (xy -0.525018 -0.839978) (xy -0.525018 -1.139952)
						(xy -0.124968 -1.139952) (xy -0.124968 -0.839978) (xy 0.124968 -0.839978) (xy 0.124968 -1.139952)
						(xy 0.525018 -1.139952) (xy 0.525018 -0.839978) (xy 0.774954 -0.839978) (xy 0.774954 -1.139952)
						(xy 1.175004 -1.139952) (xy 1.175004 -0.839978) (xy 1.225042 -0.839978) (xy 1.225042 0.295148)
						(xy 1.605026 0.295148) (xy 1.605026 0.724916) (xy 1.225042 0.724916) (xy 1.225042 1.139952)
					)
					(width 0)
					(fill yes)
				)
			)
		)
		(zone
			(layer "F.Cu")
			(hatch none 0.5)
			(connect_pads
				(clearance 0)
			)
			(min_thickness 0.25)
			(keepout
				(tracks allowed)
				(vias not_allowed)
				(pads allowed)
				(copperpour not_allowed)
				(footprints allowed)
			)
			(placement
				(enabled no)
				(sheetname "")
			)
			(fill
				(thermal_gap 0.5)
				(thermal_bridge_width 0.5)
				(island_removal_mode 0)
			)
			(polygon
				(pts
					(xy 35.76447 -112.654334) (xy 35.76447 -115.651534) (xy 36.14547 -115.651534) (xy 36.14547 -112.654334)
				)
			)
		)
		(zone
			(layer "F.Cu")
			(hatch none 0.5)
			(connect_pads
				(clearance 0)
			)
			(min_thickness 0.25)
			(keepout
				(tracks not_allowed)
				(vias allowed)
				(pads allowed)
				(copperpour not_allowed)
				(footprints allowed)
			)
			(placement
				(enabled no)
				(sheetname "")
			)
			(fill
				(thermal_gap 0.5)
				(thermal_bridge_width 0.5)
				(island_removal_mode 0)
			)
			(polygon
				(pts
					(xy 36.14547 -112.654334) (xy 36.14547 -115.651534) (xy 35.76447 -115.651534) (xy 35.76447 -112.654334)
				)
			)
		)
	)
	(footprint ""
		(layer "F.Cu")
		(at 59.67476 -185.205624 90)
		(property "Reference" "C706"
			(at 4.006088 -0.367538 90)
			(unlocked yes)
			(layer "F.SilkS")
			(effects
				(font
					(size 0.7874 0.5842)
					(thickness 0.1524)
				)
				(justify left)
			)
		)
		(property "Value" ""
			(at 0 0 90)
			(layer "F.Fab")
			(effects
				(font
					(size 1.27 1.27)
				)
			)
		)
		(duplicate_pad_numbers_are_jumpers no)
		(fp_line
			(start 0.7874 -0.4064)
			(end 0.7874 0.4064)
			(stroke
				(width 0.1524)
				(type default)
			)
			(layer "F.SilkS")
		)
		(fp_line
			(start -0.7874 -0.4064)
			(end 0.7874 -0.4064)
			(stroke
				(width 0.1524)
				(type default)
			)
			(layer "F.SilkS")
		)
		(fp_line
			(start 0 0.381)
			(end 0 -0.381)
			(stroke
				(width 0.1524)
				(type default)
			)
			(layer "F.SilkS")
		)
		(fp_line
			(start 0.7874 0.4064)
			(end -0.7874 0.4064)
			(stroke
				(width 0.1524)
				(type default)
			)
			(layer "F.SilkS")
		)
		(fp_line
			(start -0.7874 0.4064)
			(end -0.7874 -0.4064)
			(stroke
				(width 0.1524)
				(type default)
			)
			(layer "F.SilkS")
		)
		(fp_poly
			(pts
				(xy -0.5334 0.254) (xy -0.635 0.254) (xy -0.635 0.2286) (xy -0.635 -0.254) (xy -0.5334 -0.254) (xy -0.5334 -0.2794)
				(xy 0.5334 -0.2794) (xy 0.5334 -0.254) (xy 0.635 -0.254) (xy 0.635 0.254) (xy 0.5334 0.254) (xy 0.5334 0.2794)
				(xy -0.508 0.2794) (xy -0.5334 0.2794)
			)
			(stroke
				(width 0)
				(type default)
			)
			(fill no)
			(layer "F.CrtYd")
		)
		(pad "1" smd rect
			(at 0.40005 0 90)
			(size 0.4572 0.508)
			(layers "F.Cu" "F.Mask" "F.Paste")
			(net "UART_T2_NODE3_RXD")
		)
		(pad "2" smd rect
			(at -0.40005 0 90)
			(size 0.4572 0.508)
			(layers "F.Cu" "F.Mask" "F.Paste")
			(net "GND")
		)
	)
	(footprint ""
		(layer "F.Cu")
		(at 15.248128 -58.485532 90)
		(property "Reference" "C507"
			(at -3.044952 -1.283462 90)
			(unlocked yes)
			(layer "F.SilkS")
			(effects
				(font
					(size 0.7874 0.5842)
					(thickness 0.1524)
				)
				(justify left)
			)
		)
		(property "Value" ""
			(at 0 0 90)
			(layer "F.Fab")
			(effects
				(font
					(size 1.27 1.27)
				)
			)
		)
		(duplicate_pad_numbers_are_jumpers no)
		(fp_line
			(start 0.7874 -0.4064)
			(end 0.7874 0.4064)
			(stroke
				(width 0.1524)
				(type default)
			)
			(layer "F.SilkS")
		)
		(fp_line
			(start -0.7874 -0.4064)
			(end 0.7874 -0.4064)
			(stroke
				(width 0.1524)
				(type default)
			)
			(layer "F.SilkS")
		)
		(fp_line
			(start 0 0.381)
			(end 0 -0.381)
			(stroke
				(width 0.1524)
				(type default)
			)
			(layer "F.SilkS")
		)
		(fp_line
			(start 0.7874 0.4064)
			(end -0.7874 0.4064)
			(stroke
				(width 0.1524)
				(type default)
			)
			(layer "F.SilkS")
		)
		(fp_line
			(start -0.7874 0.4064)
			(end -0.7874 -0.4064)
			(stroke
				(width 0.1524)
				(type default)
			)
			(layer "F.SilkS")
		)
		(fp_poly
			(pts
				(xy -0.5334 0.254) (xy -0.635 0.254) (xy -0.635 0.2286) (xy -0.635 -0.254) (xy -0.5334 -0.254) (xy -0.5334 -0.2794)
				(xy 0.5334 -0.2794) (xy 0.5334 -0.254) (xy 0.635 -0.254) (xy 0.635 0.254) (xy 0.5334 0.254) (xy 0.5334 0.2794)
				(xy -0.508 0.2794) (xy -0.5334 0.2794)
			)
			(stroke
				(width 0)
				(type default)
			)
			(fill no)
			(layer "F.CrtYd")
		)
		(pad "1" smd rect
			(at 0.40005 0 90)
			(size 0.4572 0.508)
			(layers "F.Cu" "F.Mask" "F.Paste")
			(net "CRT_VSYNC")
		)
		(pad "2" smd rect
			(at -0.40005 0 90)
			(size 0.4572 0.508)
			(layers "F.Cu" "F.Mask" "F.Paste")
			(net "GND")
		)
	)
	(footprint ""
		(layer "F.Cu")
		(at 110.60176 -188.126624 90)
		(property "Reference" "C650"
			(at 5.151882 0.791972 90)
			(unlocked yes)
			(layer "F.SilkS")
			(effects
				(font
					(size 0.7874 0.5842)
					(thickness 0.1524)
				)
				(justify left)
			)
		)
		(property "Value" ""
			(at 0 0 90)
			(layer "F.Fab")
			(effects
				(font
					(size 1.27 1.27)
				)
			)
		)
		(duplicate_pad_numbers_are_jumpers no)
		(fp_line
			(start 0.7874 -0.4064)
			(end 0.7874 0.4064)
			(stroke
				(width 0.1524)
				(type default)
			)
			(layer "F.SilkS")
		)
		(fp_line
			(start -0.7874 -0.4064)
			(end 0.7874 -0.4064)
			(stroke
				(width 0.1524)
				(type default)
			)
			(layer "F.SilkS")
		)
		(fp_line
			(start 0 0.381)
			(end 0 -0.381)
			(stroke
				(width 0.1524)
				(type default)
			)
			(layer "F.SilkS")
		)
		(fp_line
			(start 0.7874 0.4064)
			(end -0.7874 0.4064)
			(stroke
				(width 0.1524)
				(type default)
			)
			(layer "F.SilkS")
		)
		(fp_line
			(start -0.7874 0.4064)
			(end -0.7874 -0.4064)
			(stroke
				(width 0.1524)
				(type default)
			)
			(layer "F.SilkS")
		)
		(fp_poly
			(pts
				(xy -0.5334 0.254) (xy -0.635 0.254) (xy -0.635 0.2286) (xy -0.635 -0.254) (xy -0.5334 -0.254) (xy -0.5334 -0.2794)
				(xy 0.5334 -0.2794) (xy 0.5334 -0.254) (xy 0.635 -0.254) (xy 0.635 0.254) (xy 0.5334 0.254) (xy 0.5334 0.2794)
				(xy -0.508 0.2794) (xy -0.5334 0.2794)
			)
			(stroke
				(width 0)
				(type default)
			)
			(fill no)
			(layer "F.CrtYd")
		)
		(pad "1" smd rect
			(at 0.40005 0 90)
			(size 0.4572 0.508)
			(layers "F.Cu" "F.Mask" "F.Paste")
			(net "T6_NODE2_EN_R")
		)
		(pad "2" smd rect
			(at -0.40005 0 90)
			(size 0.4572 0.508)
			(layers "F.Cu" "F.Mask" "F.Paste")
			(net "GND")
		)
	)
	(footprint ""
		(layer "F.Cu")
		(at 24.375872 -94.661228 90)
		(property "Reference" "R1151"
			(at -1.1557 2.558542 90)
			(unlocked yes)
			(layer "F.SilkS")
			(effects
				(font
					(size 0.7874 0.5842)
					(thickness 0.1524)
				)
				(justify left)
			)
		)
		(property "Value" ""
			(at 0 0 90)
			(layer "F.Fab")
			(effects
				(font
					(size 1.27 1.27)
				)
			)
		)
		(duplicate_pad_numbers_are_jumpers no)
		(fp_line
			(start 0.7874 -0.4064)
			(end 0.7874 0.4064)
			(stroke
				(width 0.1524)
				(type default)
			)
			(layer "F.SilkS")
		)
		(fp_line
			(start -0.7874 -0.4064)
			(end 0.7874 -0.4064)
			(stroke
				(width 0.1524)
				(type default)
			)
			(layer "F.SilkS")
		)
		(fp_line
			(start 0.7874 0.4064)
			(end -0.7874 0.4064)
			(stroke
				(width 0.1524)
				(type default)
			)
			(layer "F.SilkS")
		)
		(fp_line
			(start -0.7874 0.4064)
			(end -0.7874 -0.4064)
			(stroke
				(width 0.1524)
				(type default)
			)
			(layer "F.SilkS")
		)
		(fp_poly
			(pts
				(xy -0.508 0.2794) (xy -0.508 0.2286) (xy -0.635 0.2286) (xy -0.635 -0.254) (xy -0.5334 -0.254)
				(xy -0.5334 -0.2794) (xy 0.5334 -0.2794) (xy 0.5334 -0.254) (xy 0.635 -0.254) (xy 0.635 0.254) (xy 0.5334 0.254)
				(xy 0.5334 0.2794)
			)
			(stroke
				(width 0)
				(type default)
			)
			(fill no)
			(layer "F.CrtYd")
		)
		(pad "1" smd rect
			(at 0.40005 0 90)
			(size 0.4572 0.508)
			(layers "F.Cu" "F.Mask" "F.Paste")
			(net "N43448372")
		)
		(pad "2" smd rect
			(at -0.40005 0 90)
			(size 0.4572 0.508)
			(layers "F.Cu" "F.Mask" "F.Paste")
			(net "GND")
		)
	)
	(footprint ""
		(layer "F.Cu")
		(at 20.413726 -64.072516 -90)
		(property "Reference" "R633"
			(at 0.250698 -2.623058 90)
			(unlocked yes)
			(layer "F.SilkS")
			(effects
				(font
					(size 0.7874 0.5842)
					(thickness 0.1524)
				)
				(justify left)
			)
		)
		(property "Value" ""
			(at 0 0 270)
			(layer "F.Fab")
			(effects
				(font
					(size 1.27 1.27)
				)
			)
		)
		(duplicate_pad_numbers_are_jumpers no)
		(fp_line
			(start -0.7874 0.4064)
			(end -0.7874 -0.4064)
			(stroke
				(width 0.1524)
				(type default)
			)
			(layer "F.SilkS")
		)
		(fp_line
			(start 0.7874 0.4064)
			(end -0.7874 0.4064)
			(stroke
				(width 0.1524)
				(type default)
			)
			(layer "F.SilkS")
		)
		(fp_line
			(start -0.7874 -0.4064)
			(end 0.7874 -0.4064)
			(stroke
				(width 0.1524)
				(type default)
			)
			(layer "F.SilkS")
		)
		(fp_line
			(start 0.7874 -0.4064)
			(end 0.7874 0.4064)
			(stroke
				(width 0.1524)
				(type default)
			)
			(layer "F.SilkS")
		)
		(fp_poly
			(pts
				(xy -0.508 0.2794) (xy -0.508 0.2286) (xy -0.635 0.2286) (xy -0.635 -0.254) (xy -0.5334 -0.254)
				(xy -0.5334 -0.2794) (xy 0.5334 -0.2794) (xy 0.5334 -0.254) (xy 0.635 -0.254) (xy 0.635 0.254) (xy 0.5334 0.254)
				(xy 0.5334 0.2794)
			)
			(stroke
				(width 0)
				(type default)
			)
			(fill no)
			(layer "F.CrtYd")
		)
		(pad "1" smd rect
			(at 0.40005 0 270)
			(size 0.4572 0.508)
			(layers "F.Cu" "F.Mask" "F.Paste")
			(net "P3V3_NODE1")
		)
		(pad "2" smd rect
			(at -0.40005 0 270)
			(size 0.4572 0.508)
			(layers "F.Cu" "F.Mask" "F.Paste")
			(net "SMB_BMC_NODE1_DDC_CLK")
		)
	)
	(footprint ""
		(layer "F.Cu")
		(at 172.961046 -135.132064)
		(property "Reference" "Q41"
			(at 13.231368 0.52451 0)
			(unlocked yes)
			(layer "F.SilkS")
			(effects
				(font
					(size 0.7874 0.5842)
					(thickness 0.1524)
				)
				(justify left)
			)
		)
		(property "Value" ""
			(at 0 0 0)
			(layer "F.Fab")
			(effects
				(font
					(size 1.27 1.27)
				)
			)
		)
		(duplicate_pad_numbers_are_jumpers no)
		(fp_line
			(start -0.5842 -0.5842)
			(end 2.584196 -0.5842)
			(stroke
				(width 0.1524)
				(type default)
			)
			(layer "F.SilkS")
		)
		(fp_line
			(start -0.5842 2.48412)
			(end -0.5842 -0.5842)
			(stroke
				(width 0.1524)
				(type default)
			)
			(layer "F.SilkS")
		)
		(fp_line
			(start 2.584196 -0.5842)
			(end 2.584196 2.48412)
			(stroke
				(width 0.1524)
				(type default)
			)
			(layer "F.SilkS")
		)
		(fp_line
			(start 2.584196 2.48412)
			(end -0.5842 2.48412)
			(stroke
				(width 0.1524)
				(type default)
			)
			(layer "F.SilkS")
		)
		(fp_poly
			(pts
				(xy -0.508 -0.4572) (xy 0.299974 -0.4572) (xy 0.299974 -0.54991) (xy 1.700022 -0.54991) (xy 1.700022 0.49276)
				(xy 2.507996 0.49276) (xy 2.507996 1.40716) (xy 1.700022 1.40716) (xy 1.700022 2.450084) (xy 0.299974 2.450084)
				(xy 0.299974 2.35712) (xy -0.508 2.35712)
			)
			(stroke
				(width 0)
				(type default)
			)
			(fill no)
			(layer "F.CrtYd")
		)
		(fp_line
			(start 0.299974 -0.54991)
			(end 1.700022 -0.54991)
			(stroke
				(width 0.1)
				(type default)
			)
			(layer "F.Fab")
		)
		(fp_line
			(start 0.299974 2.450084)
			(end 0.299974 -0.54991)
			(stroke
				(width 0.1)
				(type default)
			)
			(layer "F.Fab")
		)
		(fp_line
			(start 1.700022 -0.54991)
			(end 1.700022 2.450084)
			(stroke
				(width 0.1)
				(type default)
			)
			(layer "F.Fab")
		)
		(fp_line
			(start 1.700022 2.450084)
			(end 0.299974 2.450084)
			(stroke
				(width 0.1)
				(type default)
			)
			(layer "F.Fab")
		)
		(fp_text user "B"
			(at -0.333248 -1.066038 0)
			(unlocked yes)
			(layer "F.SilkS")
			(effects
				(font
					(size 0.635 0.4064)
					(thickness 0.1524)
				)
				(justify left)
			)
		)
		(fp_text user "E"
			(at 0.663448 1.959102 0)
			(unlocked yes)
			(layer "F.SilkS")
			(effects
				(font
					(size 0.635 0.4064)
					(thickness 0.1524)
				)
				(justify left)
			)
		)
		(fp_text user "C"
			(at 2.774442 0.893318 0)
			(unlocked yes)
			(layer "F.SilkS")
			(effects
				(font
					(size 0.635 0.4064)
					(thickness 0.1524)
				)
				(justify left)
			)
		)
		(fp_text user "E"
			(at -1.5748 1.95707 0)
			(unlocked yes)
			(layer "F.Fab")
			(effects
				(font
					(size 0.7874 0.5842)
					(thickness 0.000001)
				)
				(justify left)
			)
		)
		(fp_text user "B"
			(at -1.5494 0.00127 0)
			(unlocked yes)
			(layer "F.Fab")
			(effects
				(font
					(size 0.7874 0.5842)
					(thickness 0.000001)
				)
				(justify left)
			)
		)
		(fp_text user "C"
			(at 2.8702 0.99187 0)
			(unlocked yes)
			(layer "F.Fab")
			(effects
				(font
					(size 0.7874 0.5842)
					(thickness 0.000001)
				)
				(justify left)
			)
		)
		(pad "B" smd rect
			(at 0 0 90)
			(size 0.8128 0.9144)
			(layers "F.Cu" "F.Mask" "F.Paste")
			(net "N41777080")
		)
		(pad "C" smd rect
			(at 1.999996 0.94996 90)
			(size 0.8128 0.9144)
			(layers "F.Cu" "F.Mask" "F.Paste")
			(net "CPLD_CPU_THRMTRIP_N")
		)
		(pad "E" smd rect
			(at 0 1.89992 90)
			(size 0.8128 0.9144)
			(layers "F.Cu" "F.Mask" "F.Paste")
			(net "N41777073")
		)
	)
)
